# T6G (Grand Teton) — schematic netlist excerpt (pin names and nets, part order shuffled) for the footprints in the layout excerpt that follows; sources: Cadence DE-HDL packaged netlist, KiCad conversion of 04192023_DAF0TMB3IC0_F0TG_MB_C_brd_V02_OCP.brd

PC2150  Q_CAP  3900PF 50V 10% X7R  pkg C0402  page 140 : A = P12V_OCP_GATE_2 ; B = GND
R1457  Q_RES  10K 5% CHIP  pkg 0402LF  page 259 : A = P1V8_AUX ; B = PWRGD_P12V_MEM_CPU0

(kicad_pcb
	(version 20260206)
	(generator "pcbnew")
	(generator_version "10.0")
	(general
		(thickness 1.6)
		(legacy_teardrops no)
	)
	(paper "A4")
	(title_block
		(title "04192023_DAF0TMB3IC0_F0TG_MB_C_brd_V02_OCP.brd")
		(comment 1 "Grand Teton / footprints 4494-4495 of 8354")
	)
	(layers
		(0 "F.Cu" signal "TOP")
		(4 "In1.Cu" signal "GND")
		(6 "In2.Cu" signal "IN1")
		(8 "In3.Cu" signal "GND1")
		(10 "In4.Cu" signal "IN2")
		(12 "In5.Cu" signal "GND2")
		(14 "In6.Cu" signal "IN3")
		(16 "In7.Cu" signal "GND3")
		(18 "In8.Cu" signal "VCC")
		(20 "In9.Cu" signal "VCC1")
		(22 "In10.Cu" signal "GND4")
		(24 "In11.Cu" signal "IN4")
		(26 "In12.Cu" signal "GND5")
		(28 "In13.Cu" signal "IN5")
		(30 "In14.Cu" signal "GND6")
		(32 "In15.Cu" signal "IN6")
		(34 "In16.Cu" signal "GND7")
		(2 "B.Cu" signal "BOTTOM")
		(9 "F.Adhes" user "F.Adhesive")
		(11 "B.Adhes" user "B.Adhesive")
		(13 "F.Paste" user "Package Geometry/Pastemask Top")
		(15 "B.Paste" user "Package Geometry/Pastemask Bottom")
		(5 "F.SilkS" user "Ref Des/Silkscreen Top")
		(7 "B.SilkS" user "Ref Des/Silkscreen Bottom")
		(1 "F.Mask" user "Board Geometry/Soldermask Top")
		(3 "B.Mask" user "Board Geometry/Soldermask Bottom")
		(17 "Dwgs.User" user "User.Drawings")
		(19 "Cmts.User" user "User.Comments")
		(21 "Eco1.User" user "User.Eco1")
		(23 "Eco2.User" user "User.Eco2")
		(25 "Edge.Cuts" user "Board Geometry/Outline")
		(27 "Margin" user)
		(31 "F.CrtYd" user "Package Geometry/Place Bound Top")
		(29 "B.CrtYd" user "Package Geometry/Place Bound Bottom")
		(35 "F.Fab" user "Ref Des/Assembly Top")
		(33 "B.Fab" user "Ref Des/Assembly Bottom")
	)
	(footprint ""
		(layer "F.Cu")
		(at 80.913478 -23.317962)
		(property "Reference" "PC2150"
			(at 0 0 0)
			(layer "F.SilkS")
			(hide yes)
			(effects
				(font
					(size 1.27 1.27)
				)
			)
		)
		(property "Value" ""
			(at 0 0 0)
			(layer "F.Fab")
			(effects
				(font
					(size 1.27 1.27)
				)
			)
		)
		(duplicate_pad_numbers_are_jumpers no)
		(fp_line
			(start -0.7874 -0.4064)
			(end 0.7874 -0.4064)
			(stroke
				(width 0.1524)
				(type default)
			)
			(layer "F.SilkS")
		)
		(fp_line
			(start -0.7874 0.4064)
			(end -0.7874 -0.4064)
			(stroke
				(width 0.1524)
				(type default)
			)
			(layer "F.SilkS")
		)
		(fp_line
			(start 0.7874 -0.4064)
			(end 0.7874 0.4064)
			(stroke
				(width 0.1524)
				(type default)
			)
			(layer "F.SilkS")
		)
		(fp_line
			(start 0.7874 0.4064)
			(end -0.7874 0.4064)
			(stroke
				(width 0.1524)
				(type default)
			)
			(layer "F.SilkS")
		)
		(fp_line
			(start -0.67945 -0.305054)
			(end -0.12065 -0.305054)
			(stroke
				(width 0.1)
				(type default)
			)
			(layer "F.Fab")
		)
		(fp_line
			(start -0.67945 0.3048)
			(end -0.67945 -0.305054)
			(stroke
				(width 0.1)
				(type default)
			)
			(layer "F.Fab")
		)
		(fp_line
			(start -0.12065 -0.305054)
			(end -0.12065 -0.2794)
			(stroke
				(width 0.1)
				(type default)
			)
			(layer "F.Fab")
		)
		(fp_line
			(start -0.12065 -0.2794)
			(end 0.12065 -0.2794)
			(stroke
				(width 0.1)
				(type default)
			)
			(layer "F.Fab")
		)
		(fp_line
			(start -0.12065 0.2794)
			(end -0.12065 0.3048)
			(stroke
				(width 0.1)
				(type default)
			)
			(layer "F.Fab")
		)
		(fp_line
			(start -0.12065 0.3048)
			(end -0.67945 0.3048)
			(stroke
				(width 0.1)
				(type default)
			)
			(layer "F.Fab")
		)
		(fp_line
			(start 0.120396 0.2794)
			(end -0.12065 0.2794)
			(stroke
				(width 0.1)
				(type default)
			)
			(layer "F.Fab")
		)
		(fp_line
			(start 0.120396 0.3048)
			(end 0.120396 0.2794)
			(stroke
				(width 0.1)
				(type default)
			)
			(layer "F.Fab")
		)
		(fp_line
			(start 0.12065 -0.3048)
			(end 0.67945 -0.3048)
			(stroke
				(width 0.1)
				(type default)
			)
			(layer "F.Fab")
		)
		(fp_line
			(start 0.12065 -0.2794)
			(end 0.12065 -0.3048)
			(stroke
				(width 0.1)
				(type default)
			)
			(layer "F.Fab")
		)
		(fp_line
			(start 0.67945 -0.3048)
			(end 0.67945 0.3048)
			(stroke
				(width 0.1)
				(type default)
			)
			(layer "F.Fab")
		)
		(fp_line
			(start 0.67945 0.3048)
			(end 0.120396 0.3048)
			(stroke
				(width 0.1)
				(type default)
			)
			(layer "F.Fab")
		)
		(pad "1" smd circle
			(at -0.40005 0)
			(size 0 0)
			(layers "F.Cu" "F.Mask" "F.Paste")
			(net "P12V_OCP_GATE_2")
		)
		(pad "2" smd circle
			(at 0.40005 0)
			(size 0 0)
			(layers "F.Cu" "F.Mask" "F.Paste")
			(net "GND")
		)
	)
	(footprint ""
		(layer "F.Cu")
		(at 100.884736 -127.787654 -90)
		(property "Reference" "R1457"
			(at 0 0 270)
			(layer "F.SilkS")
			(hide yes)
			(effects
				(font
					(size 1.27 1.27)
				)
			)
		)
		(property "Value" ""
			(at 0 0 270)
			(layer "F.Fab")
			(effects
				(font
					(size 1.27 1.27)
				)
			)
		)
		(duplicate_pad_numbers_are_jumpers no)
		(fp_line
			(start -0.7874 0.4064)
			(end -0.7874 -0.4064)
			(stroke
				(width 0.1524)
				(type default)
			)
			(layer "F.SilkS")
		)
		(fp_line
			(start 0.7874 0.4064)
			(end -0.7874 0.4064)
			(stroke
				(width 0.1524)
				(type default)
			)
			(layer "F.SilkS")
		)
		(fp_line
			(start -0.7874 -0.4064)
			(end 0.7874 -0.4064)
			(stroke
				(width 0.1524)
				(type default)
			)
			(layer "F.SilkS")
		)
		(fp_line
			(start 0.7874 -0.4064)
			(end 0.7874 0.4064)
			(stroke
				(width 0.1524)
				(type default)
			)
			(layer "F.SilkS")
		)
		(fp_line
			(start -0.67945 0.3048)
			(end -0.67945 -0.305054)
			(stroke
				(width 0.1)
				(type default)
			)
			(layer "F.Fab")
		)
		(fp_line
			(start -0.12065 0.3048)
			(end -0.67945 0.3048)
			(stroke
				(width 0.1)
				(type default)
			)
			(layer "F.Fab")
		)
		(fp_line
			(start 0.120396 0.3048)
			(end 0.120396 0.2794)
			(stroke
				(width 0.1)
				(type default)
			)
			(layer "F.Fab")
		)
		(fp_line
			(start 0.67945 0.3048)
			(end 0.120396 0.3048)
			(stroke
				(width 0.1)
				(type default)
			)
			(layer "F.Fab")
		)
		(fp_line
			(start -0.12065 0.2794)
			(end -0.12065 0.3048)
			(stroke
				(width 0.1)
				(type default)
			)
			(layer "F.Fab")
		)
		(fp_line
			(start 0.120396 0.2794)
			(end -0.12065 0.2794)
			(stroke
				(width 0.1)
				(type default)
			)
			(layer "F.Fab")
		)
		(fp_line
			(start -0.12065 -0.2794)
			(end 0.12065 -0.2794)
			(stroke
				(width 0.1)
				(type default)
			)
			(layer "F.Fab")
		)
		(fp_line
			(start 0.12065 -0.2794)
			(end 0.12065 -0.3048)
			(stroke
				(width 0.1)
				(type default)
			)
			(layer "F.Fab")
		)
		(fp_line
			(start 0.12065 -0.3048)
			(end 0.67945 -0.3048)
			(stroke
				(width 0.1)
				(type default)
			)
			(layer "F.Fab")
		)
		(fp_line
			(start 0.67945 -0.3048)
			(end 0.67945 0.3048)
			(stroke
				(width 0.1)
				(type default)
			)
			(layer "F.Fab")
		)
		(fp_line
			(start -0.67945 -0.305054)
			(end -0.12065 -0.305054)
			(stroke
				(width 0.1)
				(type default)
			)
			(layer "F.Fab")
		)
		(fp_line
			(start -0.12065 -0.305054)
			(end -0.12065 -0.2794)
			(stroke
				(width 0.1)
				(type default)
			)
			(layer "F.Fab")
		)
		(pad "1" smd circle
			(at -0.40005 0 270)
			(size 0 0)
			(layers "F.Cu" "F.Mask" "F.Paste")
			(net "P1V8_AUX")
		)
		(pad "2" smd circle
			(at 0.40005 0 270)
			(size 0 0)
			(layers "F.Cu" "F.Mask" "F.Paste")
			(net "PWRGD_P12V_MEM_CPU0")
		)
	)
)
